(kicad_pcb
	(version 20260206)
	(generator "pcbnew")
	(generator_version "10.0")
	(general
		(thickness 1.6)
		(legacy_teardrops no)
	)
	(paper "A4")
	(title_block
		(title "04192023_DAF0TMB3IC0_F0TG_MB_C_brd_V02_OCP.brd")
		(comment 1 "Grand Teton / footprints 391-396 of 8354")
	)
	(layers
		(0 "F.Cu" signal "TOP")
		(4 "In1.Cu" signal "GND")
		(6 "In2.Cu" signal "IN1")
		(8 "In3.Cu" signal "GND1")
		(10 "In4.Cu" signal "IN2")
		(12 "In5.Cu" signal "GND2")
		(14 "In6.Cu" signal "IN3")
		(16 "In7.Cu" signal "GND3")
		(18 "In8.Cu" signal "VCC")
		(20 "In9.Cu" signal "VCC1")
		(22 "In10.Cu" signal "GND4")
		(24 "In11.Cu" signal "IN4")
		(26 "In12.Cu" signal "GND5")
		(28 "In13.Cu" signal "IN5")
		(30 "In14.Cu" signal "GND6")
		(32 "In15.Cu" signal "IN6")
		(34 "In16.Cu" signal "GND7")
		(2 "B.Cu" signal "BOTTOM")
		(9 "F.Adhes" user "F.Adhesive")
		(11 "B.Adhes" user "B.Adhesive")
		(13 "F.Paste" user "Package Geometry/Pastemask Top")
		(15 "B.Paste" user "Package Geometry/Pastemask Bottom")
		(5 "F.SilkS" user "Ref Des/Silkscreen Top")
		(7 "B.SilkS" user "Ref Des/Silkscreen Bottom")
		(1 "F.Mask" user "Board Geometry/Soldermask Top")
		(3 "B.Mask" user "Board Geometry/Soldermask Bottom")
		(17 "Dwgs.User" user "User.Drawings")
		(19 "Cmts.User" user "User.Comments")
		(21 "Eco1.User" user "User.Eco1")
		(23 "Eco2.User" user "User.Eco2")
		(25 "Edge.Cuts" user "Board Geometry/Outline")
		(27 "Margin" user)
		(31 "F.CrtYd" user "Package Geometry/Place Bound Top")
		(29 "B.CrtYd" user "Package Geometry/Place Bound Bottom")
		(35 "F.Fab" user "Ref Des/Assembly Top")
		(33 "B.Fab" user "Ref Des/Assembly Bottom")
	)
	(footprint ""
		(layer "F.Cu")
		(at 301.124112 -351.368106 90)
		(property "Reference" "PR101"
			(at 0 0 90)
			(layer "F.SilkS")
			(hide yes)
			(effects
				(font
					(size 1.27 1.27)
				)
			)
		)
		(property "Value" ""
			(at 0 0 90)
			(layer "F.Fab")
			(effects
				(font
					(size 1.27 1.27)
				)
			)
		)
		(duplicate_pad_numbers_are_jumpers no)
		(fp_line
			(start 0.7874 -0.4064)
			(end 0.7874 0.4064)
			(stroke
				(width 0.1524)
				(type default)
			)
			(layer "F.SilkS")
		)
		(fp_line
			(start -0.7874 -0.4064)
			(end 0.7874 -0.4064)
			(stroke
				(width 0.1524)
				(type default)
			)
			(layer "F.SilkS")
		)
		(fp_line
			(start 0.7874 0.4064)
			(end -0.7874 0.4064)
			(stroke
				(width 0.1524)
				(type default)
			)
			(layer "F.SilkS")
		)
		(fp_line
			(start -0.7874 0.4064)
			(end -0.7874 -0.4064)
			(stroke
				(width 0.1524)
				(type default)
			)
			(layer "F.SilkS")
		)
		(fp_line
			(start -0.12065 -0.305054)
			(end -0.12065 -0.2794)
			(stroke
				(width 0.1)
				(type default)
			)
			(layer "F.Fab")
		)
		(fp_line
			(start -0.67945 -0.305054)
			(end -0.12065 -0.305054)
			(stroke
				(width 0.1)
				(type default)
			)
			(layer "F.Fab")
		)
		(fp_line
			(start 0.67945 -0.3048)
			(end 0.67945 0.3048)
			(stroke
				(width 0.1)
				(type default)
			)
			(layer "F.Fab")
		)
		(fp_line
			(start 0.12065 -0.3048)
			(end 0.67945 -0.3048)
			(stroke
				(width 0.1)
				(type default)
			)
			(layer "F.Fab")
		)
		(fp_line
			(start 0.12065 -0.2794)
			(end 0.12065 -0.3048)
			(stroke
				(width 0.1)
				(type default)
			)
			(layer "F.Fab")
		)
		(fp_line
			(start -0.12065 -0.2794)
			(end 0.12065 -0.2794)
			(stroke
				(width 0.1)
				(type default)
			)
			(layer "F.Fab")
		)
		(fp_line
			(start 0.120396 0.2794)
			(end -0.12065 0.2794)
			(stroke
				(width 0.1)
				(type default)
			)
			(layer "F.Fab")
		)
		(fp_line
			(start -0.12065 0.2794)
			(end -0.12065 0.3048)
			(stroke
				(width 0.1)
				(type default)
			)
			(layer "F.Fab")
		)
		(fp_line
			(start 0.67945 0.3048)
			(end 0.120396 0.3048)
			(stroke
				(width 0.1)
				(type default)
			)
			(layer "F.Fab")
		)
		(fp_line
			(start 0.120396 0.3048)
			(end 0.120396 0.2794)
			(stroke
				(width 0.1)
				(type default)
			)
			(layer "F.Fab")
		)
		(fp_line
			(start -0.12065 0.3048)
			(end -0.67945 0.3048)
			(stroke
				(width 0.1)
				(type default)
			)
			(layer "F.Fab")
		)
		(fp_line
			(start -0.67945 0.3048)
			(end -0.67945 -0.305054)
			(stroke
				(width 0.1)
				(type default)
			)
			(layer "F.Fab")
		)
		(pad "1" smd circle
			(at -0.40005 0 90)
			(size 0 0)
			(layers "F.Cu" "F.Mask" "F.Paste")
			(net "SW_PVDDIO_P0_BOOT1")
		)
		(pad "2" smd circle
			(at 0.40005 0 90)
			(size 0 0)
			(layers "F.Cu" "F.Mask" "F.Paste")
			(net "SW_PVDDIO_P0_BOOT1_R")
		)
	)
	(footprint ""
		(layer "F.Cu")
		(at 110.643924 -386.684774 -90)
		(property "Reference" "R641"
			(at 0 0 270)
			(layer "F.SilkS")
			(hide yes)
			(effects
				(font
					(size 1.27 1.27)
				)
			)
		)
		(property "Value" ""
			(at 0 0 270)
			(layer "F.Fab")
			(effects
				(font
					(size 1.27 1.27)
				)
			)
		)
		(duplicate_pad_numbers_are_jumpers no)
		(fp_line
			(start -0.32512 0.175006)
			(end -0.32512 -0.175006)
			(stroke
				(width 0.1)
				(type default)
			)
			(layer "F.Fab")
		)
		(fp_line
			(start 0.32512 0.175006)
			(end -0.32512 0.175006)
			(stroke
				(width 0.1)
				(type default)
			)
			(layer "F.Fab")
		)
		(fp_line
			(start -0.32512 -0.175006)
			(end 0.32512 -0.175006)
			(stroke
				(width 0.1)
				(type default)
			)
			(layer "F.Fab")
		)
		(fp_line
			(start 0.32512 -0.175006)
			(end 0.32512 0.175006)
			(stroke
				(width 0.1)
				(type default)
			)
			(layer "F.Fab")
		)
		(pad "1" smd rect
			(at -0.2667 0 270)
			(size 0.3048 0.381)
			(layers "F.Cu" "F.Mask" "F.Paste")
			(net "CLK_100M_RETIMER_CPU1_P3_DN")
		)
		(pad "2" smd rect
			(at 0.2667 0 90)
			(size 0.3048 0.381)
			(layers "F.Cu" "F.Mask" "F.Paste")
			(net "GND")
		)
	)
	(footprint ""
		(layer "F.Cu")
		(at 97.795842 6.063234)
		(property "Reference" "J77"
			(at 5.390642 -0.182626 0)
			(unlocked yes)
			(layer "F.SilkS")
			(effects
				(font
					(size 0.7874 0.5842)
					(thickness 0.1524)
				)
				(justify left)
			)
		)
		(property "Value" ""
			(at 0 0 0)
			(layer "F.Fab")
			(effects
				(font
					(size 1.27 1.27)
				)
			)
		)
		(duplicate_pad_numbers_are_jumpers no)
		(fp_line
			(start -1.2192 -2.06756)
			(end 1.2192 -2.06756)
			(stroke
				(width 0.1524)
				(type default)
			)
			(layer "F.SilkS")
		)
		(fp_line
			(start -1.2192 2.06756)
			(end -1.2192 -2.06756)
			(stroke
				(width 0.1524)
				(type default)
			)
			(layer "F.SilkS")
		)
		(fp_line
			(start 1.2192 -2.06756)
			(end 1.2192 2.06756)
			(stroke
				(width 0.1524)
				(type default)
			)
			(layer "F.SilkS")
		)
		(fp_line
			(start 1.2192 2.06756)
			(end -1.2192 2.06756)
			(stroke
				(width 0.1524)
				(type default)
			)
			(layer "F.SilkS")
		)
		(pad "" np_thru_hole circle
			(at -2.8829 -1.27 270)
			(size 1.0414 1.0414)
			(drill 1.0414)
			(layers "*.Cu" "*.Mask")
			(clearance 0.381)
			(thermal_gap 0.381)
		)
		(pad "" np_thru_hole circle
			(at -2.8829 1.27 270)
			(size 1.0414 1.0414)
			(drill 1.0414)
			(layers "*.Cu" "*.Mask")
			(clearance 0.381)
			(thermal_gap 0.381)
		)
		(pad "" np_thru_hole circle
			(at 3.4671 -1.27 270)
			(size 1.0414 1.0414)
			(drill 1.0414)
			(layers "*.Cu" "*.Mask")
			(clearance 0.381)
			(thermal_gap 0.381)
		)
		(pad "" np_thru_hole circle
			(at 3.4671 1.27 270)
			(size 1.0414 1.0414)
			(drill 1.0414)
			(layers "*.Cu" "*.Mask")
			(clearance 0.381)
			(thermal_gap 0.381)
		)
		(pad "1" smd rect
			(at 0.8255 -0.249936 270)
			(size 0.3048 0.508)
			(layers "F.Cu" "F.Mask" "F.Paste")
			(net "DELTA_L_85_10INCH_IN1_DP")
		)
		(pad "2" smd rect
			(at 0.8255 0.249936 270)
			(size 0.3048 0.508)
			(layers "F.Cu" "F.Mask" "F.Paste")
			(net "DELTA_L_85_10INCH_IN1_DN")
		)
		(pad "3" smd circle
			(at 0 0)
			(size 0 0)
			(layers "F.Cu" "F.Mask" "F.Paste")
			(net "DELTA_L_GND_1")
		)
		(zone
			(layer "F.Cu")
			(hatch none 0.5)
			(connect_pads
				(clearance 0)
			)
			(min_thickness 0.25)
			(keepout
				(tracks not_allowed)
				(vias allowed)
				(pads allowed)
				(copperpour not_allowed)
				(footprints allowed)
			)
			(placement
				(enabled no)
				(sheetname "")
			)
			(fill
				(thermal_gap 0.5)
				(thermal_bridge_width 0.5)
				(island_removal_mode 0)
			)
			(polygon
				(pts
					(xy 98.913442 5.514594) (xy 98.913442 5.610098) (xy 98.316542 5.610098) (xy 98.316542 6.016498)
					(xy 98.913442 6.016498) (xy 98.913442 6.10997) (xy 98.316542 6.10997) (xy 98.316542 6.51637) (xy 98.913442 6.51637)
					(xy 98.913442 6.611874) (xy 98.214942 6.611874) (xy 98.214942 5.514594)
				)
			)
		)
		(zone
			(layers "F.Cu" "B.Cu" "In1.Cu" "In2.Cu" "In3.Cu" "In4.Cu" "In5.Cu" "In6.Cu"
				"In7.Cu" "In8.Cu" "In9.Cu" "In10.Cu" "In11.Cu" "In12.Cu" "In13.Cu" "In14.Cu"
				"In15.Cu" "In16.Cu"
			)
			(hatch none 0.5)
			(connect_pads
				(clearance 0)
			)
			(min_thickness 0.25)
			(keepout
				(tracks not_allowed)
				(vias allowed)
				(pads allowed)
				(copperpour not_allowed)
				(footprints allowed)
			)
			(placement
				(enabled no)
				(sheetname "")
			)
			(fill
				(thermal_gap 0.5)
				(thermal_bridge_width 0.5)
				(island_removal_mode 0)
			)
			(polygon
				(pts
					(arc
						(start 95.840042 4.793234)
						(mid 93.985842 4.793234)
						(end 95.840042 4.793234)
					)
				)
			)
		)
		(zone
			(layers "F.Cu" "B.Cu" "In1.Cu" "In2.Cu" "In3.Cu" "In4.Cu" "In5.Cu" "In6.Cu"
				"In7.Cu" "In8.Cu" "In9.Cu" "In10.Cu" "In11.Cu" "In12.Cu" "In13.Cu" "In14.Cu"
				"In15.Cu" "In16.Cu"
			)
			(hatch none 0.5)
			(connect_pads
				(clearance 0)
			)
			(min_thickness 0.25)
			(keepout
				(tracks not_allowed)
				(vias allowed)
				(pads allowed)
				(copperpour not_allowed)
				(footprints allowed)
			)
			(placement
				(enabled no)
				(sheetname "")
			)
			(fill
				(thermal_gap 0.5)
				(thermal_bridge_width 0.5)
				(island_removal_mode 0)
			)
			(polygon
				(pts
					(arc
						(start 95.840042 7.333234)
						(mid 93.985842 7.333234)
						(end 95.840042 7.333234)
					)
				)
			)
		)
		(zone
			(layers "F.Cu" "B.Cu" "In1.Cu" "In2.Cu" "In3.Cu" "In4.Cu" "In5.Cu" "In6.Cu"
				"In7.Cu" "In8.Cu" "In9.Cu" "In10.Cu" "In11.Cu" "In12.Cu" "In13.Cu" "In14.Cu"
				"In15.Cu" "In16.Cu"
			)
			(hatch none 0.5)
			(connect_pads
				(clearance 0)
			)
			(min_thickness 0.25)
			(keepout
				(tracks not_allowed)
				(vias allowed)
				(pads allowed)
				(copperpour not_allowed)
				(footprints allowed)
			)
			(placement
				(enabled no)
				(sheetname "")
			)
			(fill
				(thermal_gap 0.5)
				(thermal_bridge_width 0.5)
				(island_removal_mode 0)
			)
			(polygon
				(pts
					(arc
						(start 102.190042 4.793234)
						(mid 100.335842 4.793234)
						(end 102.190042 4.793234)
					)
				)
			)
		)
		(zone
			(layers "F.Cu" "B.Cu" "In1.Cu" "In2.Cu" "In3.Cu" "In4.Cu" "In5.Cu" "In6.Cu"
				"In7.Cu" "In8.Cu" "In9.Cu" "In10.Cu" "In11.Cu" "In12.Cu" "In13.Cu" "In14.Cu"
				"In15.Cu" "In16.Cu"
			)
			(hatch none 0.5)
			(connect_pads
				(clearance 0)
			)
			(min_thickness 0.25)
			(keepout
				(tracks not_allowed)
				(vias allowed)
				(pads allowed)
				(copperpour not_allowed)
				(footprints allowed)
			)
			(placement
				(enabled no)
				(sheetname "")
			)
			(fill
				(thermal_gap 0.5)
				(thermal_bridge_width 0.5)
				(island_removal_mode 0)
			)
			(polygon
				(pts
					(arc
						(start 102.190042 7.333234)
						(mid 100.335842 7.333234)
						(end 102.190042 7.333234)
					)
				)
			)
		)
	)
	(footprint ""
		(layer "F.Cu")
		(at 90.825828 -141.42466 90)
		(property "Reference" "R8178"
			(at 0 0 90)
			(layer "F.SilkS")
			(hide yes)
			(effects
				(font
					(size 1.27 1.27)
				)
			)
		)
		(property "Value" ""
			(at 0 0 90)
			(layer "F.Fab")
			(effects
				(font
					(size 1.27 1.27)
				)
			)
		)
		(duplicate_pad_numbers_are_jumpers no)
		(fp_line
			(start 0.7874 -0.4064)
			(end 0.7874 0.4064)
			(stroke
				(width 0.1524)
				(type default)
			)
			(layer "F.SilkS")
		)
		(fp_line
			(start -0.7874 -0.4064)
			(end 0.7874 -0.4064)
			(stroke
				(width 0.1524)
				(type default)
			)
			(layer "F.SilkS")
		)
		(fp_line
			(start 0.7874 0.4064)
			(end -0.7874 0.4064)
			(stroke
				(width 0.1524)
				(type default)
			)
			(layer "F.SilkS")
		)
		(fp_line
			(start -0.7874 0.4064)
			(end -0.7874 -0.4064)
			(stroke
				(width 0.1524)
				(type default)
			)
			(layer "F.SilkS")
		)
		(fp_line
			(start -0.12065 -0.305054)
			(end -0.12065 -0.2794)
			(stroke
				(width 0.1)
				(type default)
			)
			(layer "F.Fab")
		)
		(fp_line
			(start -0.67945 -0.305054)
			(end -0.12065 -0.305054)
			(stroke
				(width 0.1)
				(type default)
			)
			(layer "F.Fab")
		)
		(fp_line
			(start 0.67945 -0.3048)
			(end 0.67945 0.3048)
			(stroke
				(width 0.1)
				(type default)
			)
			(layer "F.Fab")
		)
		(fp_line
			(start 0.12065 -0.3048)
			(end 0.67945 -0.3048)
			(stroke
				(width 0.1)
				(type default)
			)
			(layer "F.Fab")
		)
		(fp_line
			(start 0.12065 -0.2794)
			(end 0.12065 -0.3048)
			(stroke
				(width 0.1)
				(type default)
			)
			(layer "F.Fab")
		)
		(fp_line
			(start -0.12065 -0.2794)
			(end 0.12065 -0.2794)
			(stroke
				(width 0.1)
				(type default)
			)
			(layer "F.Fab")
		)
		(fp_line
			(start 0.120396 0.2794)
			(end -0.12065 0.2794)
			(stroke
				(width 0.1)
				(type default)
			)
			(layer "F.Fab")
		)
		(fp_line
			(start -0.12065 0.2794)
			(end -0.12065 0.3048)
			(stroke
				(width 0.1)
				(type default)
			)
			(layer "F.Fab")
		)
		(fp_line
			(start 0.67945 0.3048)
			(end 0.120396 0.3048)
			(stroke
				(width 0.1)
				(type default)
			)
			(layer "F.Fab")
		)
		(fp_line
			(start 0.120396 0.3048)
			(end 0.120396 0.2794)
			(stroke
				(width 0.1)
				(type default)
			)
			(layer "F.Fab")
		)
		(fp_line
			(start -0.12065 0.3048)
			(end -0.67945 0.3048)
			(stroke
				(width 0.1)
				(type default)
			)
			(layer "F.Fab")
		)
		(fp_line
			(start -0.67945 0.3048)
			(end -0.67945 -0.305054)
			(stroke
				(width 0.1)
				(type default)
			)
			(layer "F.Fab")
		)
		(pad "1" smd circle
			(at -0.40005 0 90)
			(size 0 0)
			(layers "F.Cu" "F.Mask" "F.Paste")
			(net "PWRGD_PVDDCR_CPU0_P1")
		)
		(pad "2" smd circle
			(at 0.40005 0 90)
			(size 0 0)
			(layers "F.Cu" "F.Mask" "F.Paste")
			(net "PWRGD_PVDDCR_CPU0_P1_R")
		)
	)
	(footprint ""
		(layer "F.Cu")
		(at 438.056782 -437.34736 90)
		(property "Reference" "R4168"
			(at 0 0 90)
			(layer "F.SilkS")
			(hide yes)
			(effects
				(font
					(size 1.27 1.27)
				)
			)
		)
		(property "Value" ""
			(at 0 0 90)
			(layer "F.Fab")
			(effects
				(font
					(size 1.27 1.27)
				)
			)
		)
		(duplicate_pad_numbers_are_jumpers no)
		(fp_line
			(start 0.7874 -0.4064)
			(end 0.7874 0.4064)
			(stroke
				(width 0.1524)
				(type default)
			)
			(layer "F.SilkS")
		)
		(fp_line
			(start -0.7874 -0.4064)
			(end 0.7874 -0.4064)
			(stroke
				(width 0.1524)
				(type default)
			)
			(layer "F.SilkS")
		)
		(fp_line
			(start 0.7874 0.4064)
			(end -0.7874 0.4064)
			(stroke
				(width 0.1524)
				(type default)
			)
			(layer "F.SilkS")
		)
		(fp_line
			(start -0.7874 0.4064)
			(end -0.7874 -0.4064)
			(stroke
				(width 0.1524)
				(type default)
			)
			(layer "F.SilkS")
		)
		(fp_line
			(start -0.12065 -0.305054)
			(end -0.12065 -0.2794)
			(stroke
				(width 0.1)
				(type default)
			)
			(layer "F.Fab")
		)
		(fp_line
			(start -0.67945 -0.305054)
			(end -0.12065 -0.305054)
			(stroke
				(width 0.1)
				(type default)
			)
			(layer "F.Fab")
		)
		(fp_line
			(start 0.67945 -0.3048)
			(end 0.67945 0.3048)
			(stroke
				(width 0.1)
				(type default)
			)
			(layer "F.Fab")
		)
		(fp_line
			(start 0.12065 -0.3048)
			(end 0.67945 -0.3048)
			(stroke
				(width 0.1)
				(type default)
			)
			(layer "F.Fab")
		)
		(fp_line
			(start 0.12065 -0.2794)
			(end 0.12065 -0.3048)
			(stroke
				(width 0.1)
				(type default)
			)
			(layer "F.Fab")
		)
		(fp_line
			(start -0.12065 -0.2794)
			(end 0.12065 -0.2794)
			(stroke
				(width 0.1)
				(type default)
			)
			(layer "F.Fab")
		)
		(fp_line
			(start 0.120396 0.2794)
			(end -0.12065 0.2794)
			(stroke
				(width 0.1)
				(type default)
			)
			(layer "F.Fab")
		)
		(fp_line
			(start -0.12065 0.2794)
			(end -0.12065 0.3048)
			(stroke
				(width 0.1)
				(type default)
			)
			(layer "F.Fab")
		)
		(fp_line
			(start 0.67945 0.3048)
			(end 0.120396 0.3048)
			(stroke
				(width 0.1)
				(type default)
			)
			(layer "F.Fab")
		)
		(fp_line
			(start 0.120396 0.3048)
			(end 0.120396 0.2794)
			(stroke
				(width 0.1)
				(type default)
			)
			(layer "F.Fab")
		)
		(fp_line
			(start -0.12065 0.3048)
			(end -0.67945 0.3048)
			(stroke
				(width 0.1)
				(type default)
			)
			(layer "F.Fab")
		)
		(fp_line
			(start -0.67945 0.3048)
			(end -0.67945 -0.305054)
			(stroke
				(width 0.1)
				(type default)
			)
			(layer "F.Fab")
		)
		(pad "1" smd circle
			(at -0.40005 0 90)
			(size 0 0)
			(layers "F.Cu" "F.Mask" "F.Paste")
			(net "P3V3_AUX")
		)
		(pad "2" smd circle
			(at 0.40005 0 90)
			(size 0 0)
			(layers "F.Cu" "F.Mask" "F.Paste")
			(net "GPU_3V3IO_RSVD4_ISO")
		)
	)
	(footprint ""
		(layer "F.Cu")
		(at 120.396 -421.513 180)
		(property "Reference" "R3465"
			(at 0 0 180)
			(layer "F.SilkS")
			(hide yes)
			(effects
				(font
					(size 1.27 1.27)
				)
			)
		)
		(property "Value" ""
			(at 0 0 180)
			(layer "F.Fab")
			(effects
				(font
					(size 1.27 1.27)
				)
			)
		)
		(duplicate_pad_numbers_are_jumpers no)
		(fp_line
			(start 0.7874 0.4064)
			(end -0.7874 0.4064)
			(stroke
				(width 0.1524)
				(type default)
			)
			(layer "F.SilkS")
		)
		(fp_line
			(start 0.7874 -0.4064)
			(end 0.7874 0.4064)
			(stroke
				(width 0.1524)
				(type default)
			)
			(layer "F.SilkS")
		)
		(fp_line
			(start -0.7874 0.4064)
			(end -0.7874 -0.4064)
			(stroke
				(width 0.1524)
				(type default)
			)
			(layer "F.SilkS")
		)
		(fp_line
			(start -0.7874 -0.4064)
			(end 0.7874 -0.4064)
			(stroke
				(width 0.1524)
				(type default)
			)
			(layer "F.SilkS")
		)
		(fp_line
			(start 0.67945 0.3048)
			(end 0.120396 0.3048)
			(stroke
				(width 0.1)
				(type default)
			)
			(layer "F.Fab")
		)
		(fp_line
			(start 0.67945 -0.3048)
			(end 0.67945 0.3048)
			(stroke
				(width 0.1)
				(type default)
			)
			(layer "F.Fab")
		)
		(fp_line
			(start 0.12065 -0.2794)
			(end 0.12065 -0.3048)
			(stroke
				(width 0.1)
				(type default)
			)
			(layer "F.Fab")
		)
		(fp_line
			(start 0.12065 -0.3048)
			(end 0.67945 -0.3048)
			(stroke
				(width 0.1)
				(type default)
			)
			(layer "F.Fab")
		)
		(fp_line
			(start 0.120396 0.3048)
			(end 0.120396 0.2794)
			(stroke
				(width 0.1)
				(type default)
			)
			(layer "F.Fab")
		)
		(fp_line
			(start 0.120396 0.2794)
			(end -0.12065 0.2794)
			(stroke
				(width 0.1)
				(type default)
			)
			(layer "F.Fab")
		)
		(fp_line
			(start -0.12065 0.3048)
			(end -0.67945 0.3048)
			(stroke
				(width 0.1)
				(type default)
			)
			(layer "F.Fab")
		)
		(fp_line
			(start -0.12065 0.2794)
			(end -0.12065 0.3048)
			(stroke
				(width 0.1)
				(type default)
			)
			(layer "F.Fab")
		)
		(fp_line
			(start -0.12065 -0.2794)
			(end 0.12065 -0.2794)
			(stroke
				(width 0.1)
				(type default)
			)
			(layer "F.Fab")
		)
		(fp_line
			(start -0.12065 -0.305054)
			(end -0.12065 -0.2794)
			(stroke
				(width 0.1)
				(type default)
			)
			(layer "F.Fab")
		)
		(fp_line
			(start -0.67945 0.3048)
			(end -0.67945 -0.305054)
			(stroke
				(width 0.1)
				(type default)
			)
			(layer "F.Fab")
		)
		(fp_line
			(start -0.67945 -0.305054)
			(end -0.12065 -0.305054)
			(stroke
				(width 0.1)
				(type default)
			)
			(layer "F.Fab")
		)
		(pad "1" smd circle
			(at -0.40005 0 180)
			(size 0 0)
			(layers "F.Cu" "F.Mask" "F.Paste")
			(net "P3V3_AUX")
		)
		(pad "2" smd circle
			(at 0.40005 0 180)
			(size 0 0)
			(layers "F.Cu" "F.Mask" "F.Paste")
			(net "GPU_HMC_PRSNT_N")
		)
	)
)
